(kicad_pcb
	(version 20260206)
	(generator "pcbnew")
	(generator_version "10.0")
	(general
		(thickness 1.6)
		(legacy_teardrops no)
	)
	(paper "A4")
	(title_block
		(title "04192023_DAF0TMB3IC0_F0TG_MB_C_brd_V02_OCP.brd")
		(comment 1 "Grand Teton / footprints 7333-7339 of 8354")
	)
	(layers
		(0 "F.Cu" signal "TOP")
		(4 "In1.Cu" signal "GND")
		(6 "In2.Cu" signal "IN1")
		(8 "In3.Cu" signal "GND1")
		(10 "In4.Cu" signal "IN2")
		(12 "In5.Cu" signal "GND2")
		(14 "In6.Cu" signal "IN3")
		(16 "In7.Cu" signal "GND3")
		(18 "In8.Cu" signal "VCC")
		(20 "In9.Cu" signal "VCC1")
		(22 "In10.Cu" signal "GND4")
		(24 "In11.Cu" signal "IN4")
		(26 "In12.Cu" signal "GND5")
		(28 "In13.Cu" signal "IN5")
		(30 "In14.Cu" signal "GND6")
		(32 "In15.Cu" signal "IN6")
		(34 "In16.Cu" signal "GND7")
		(2 "B.Cu" signal "BOTTOM")
		(9 "F.Adhes" user "F.Adhesive")
		(11 "B.Adhes" user "B.Adhesive")
		(13 "F.Paste" user "Package Geometry/Pastemask Top")
		(15 "B.Paste" user "Package Geometry/Pastemask Bottom")
		(5 "F.SilkS" user "Ref Des/Silkscreen Top")
		(7 "B.SilkS" user "Ref Des/Silkscreen Bottom")
		(1 "F.Mask" user "Board Geometry/Soldermask Top")
		(3 "B.Mask" user "Board Geometry/Soldermask Bottom")
		(17 "Dwgs.User" user "User.Drawings")
		(19 "Cmts.User" user "User.Comments")
		(21 "Eco1.User" user "User.Eco1")
		(23 "Eco2.User" user "User.Eco2")
		(25 "Edge.Cuts" user "Board Geometry/Outline")
		(27 "Margin" user)
		(31 "F.CrtYd" user "Package Geometry/Place Bound Top")
		(29 "B.CrtYd" user "Package Geometry/Place Bound Bottom")
		(35 "F.Fab" user "Ref Des/Assembly Top")
		(33 "B.Fab" user "Ref Des/Assembly Bottom")
	)
	(footprint ""
		(layer "B.Cu")
		(at 197.345808 -124.877576 180)
		(property "Reference" "R6115"
			(at 0 0 0)
			(layer "B.SilkS")
			(hide yes)
			(effects
				(font
					(size 1.27 1.27)
				)
				(justify mirror)
			)
		)
		(property "Value" ""
			(at 0 0 0)
			(layer "B.Fab")
			(effects
				(font
					(size 1.27 1.27)
				)
				(justify mirror)
			)
		)
		(duplicate_pad_numbers_are_jumpers no)
		(fp_line
			(start 0.7874 0.4064)
			(end 0.7874 -0.4064)
			(stroke
				(width 0.1524)
				(type default)
			)
			(layer "B.SilkS")
		)
		(fp_line
			(start 0.7874 -0.4064)
			(end -0.7874 -0.4064)
			(stroke
				(width 0.1524)
				(type default)
			)
			(layer "B.SilkS")
		)
		(fp_line
			(start -0.7874 0.4064)
			(end 0.7874 0.4064)
			(stroke
				(width 0.1524)
				(type default)
			)
			(layer "B.SilkS")
		)
		(fp_line
			(start -0.7874 -0.4064)
			(end -0.7874 0.4064)
			(stroke
				(width 0.1524)
				(type default)
			)
			(layer "B.SilkS")
		)
		(fp_line
			(start 0.67945 0.3048)
			(end 0.67945 -0.305054)
			(stroke
				(width 0.1)
				(type default)
			)
			(layer "B.Fab")
		)
		(fp_line
			(start 0.67945 -0.305054)
			(end 0.12065 -0.305054)
			(stroke
				(width 0.1)
				(type default)
			)
			(layer "B.Fab")
		)
		(fp_line
			(start 0.12065 0.3048)
			(end 0.67945 0.3048)
			(stroke
				(width 0.1)
				(type default)
			)
			(layer "B.Fab")
		)
		(fp_line
			(start 0.12065 0.2794)
			(end 0.12065 0.3048)
			(stroke
				(width 0.1)
				(type default)
			)
			(layer "B.Fab")
		)
		(fp_line
			(start 0.12065 -0.2794)
			(end -0.12065 -0.2794)
			(stroke
				(width 0.1)
				(type default)
			)
			(layer "B.Fab")
		)
		(fp_line
			(start 0.12065 -0.305054)
			(end 0.12065 -0.2794)
			(stroke
				(width 0.1)
				(type default)
			)
			(layer "B.Fab")
		)
		(fp_line
			(start -0.120396 0.3048)
			(end -0.120396 0.2794)
			(stroke
				(width 0.1)
				(type default)
			)
			(layer "B.Fab")
		)
		(fp_line
			(start -0.120396 0.2794)
			(end 0.12065 0.2794)
			(stroke
				(width 0.1)
				(type default)
			)
			(layer "B.Fab")
		)
		(fp_line
			(start -0.12065 -0.2794)
			(end -0.12065 -0.3048)
			(stroke
				(width 0.1)
				(type default)
			)
			(layer "B.Fab")
		)
		(fp_line
			(start -0.12065 -0.3048)
			(end -0.67945 -0.3048)
			(stroke
				(width 0.1)
				(type default)
			)
			(layer "B.Fab")
		)
		(fp_line
			(start -0.67945 0.3048)
			(end -0.120396 0.3048)
			(stroke
				(width 0.1)
				(type default)
			)
			(layer "B.Fab")
		)
		(fp_line
			(start -0.67945 -0.3048)
			(end -0.67945 0.3048)
			(stroke
				(width 0.1)
				(type default)
			)
			(layer "B.Fab")
		)
		(pad "1" smd circle
			(at 0.40005 0)
			(size 0 0)
			(layers "B.Cu" "B.Mask" "B.Paste")
			(net "RST_PERST_CPU1_SWB_N")
		)
		(pad "2" smd circle
			(at -0.40005 0)
			(size 0 0)
			(layers "B.Cu" "B.Mask" "B.Paste")
			(net "GND")
		)
	)
	(footprint ""
		(layer "B.Cu")
		(at 188.849 -100.294948 -90)
		(property "Reference" "R232"
			(at 0 0 90)
			(layer "B.SilkS")
			(hide yes)
			(effects
				(font
					(size 1.27 1.27)
				)
				(justify mirror)
			)
		)
		(property "Value" ""
			(at 0 0 90)
			(layer "B.Fab")
			(effects
				(font
					(size 1.27 1.27)
				)
				(justify mirror)
			)
		)
		(duplicate_pad_numbers_are_jumpers no)
		(fp_line
			(start -0.7874 0.4064)
			(end 0.7874 0.4064)
			(stroke
				(width 0.1524)
				(type default)
			)
			(layer "B.SilkS")
		)
		(fp_line
			(start 0.7874 0.4064)
			(end 0.7874 -0.4064)
			(stroke
				(width 0.1524)
				(type default)
			)
			(layer "B.SilkS")
		)
		(fp_line
			(start -0.7874 -0.4064)
			(end -0.7874 0.4064)
			(stroke
				(width 0.1524)
				(type default)
			)
			(layer "B.SilkS")
		)
		(fp_line
			(start 0.7874 -0.4064)
			(end -0.7874 -0.4064)
			(stroke
				(width 0.1524)
				(type default)
			)
			(layer "B.SilkS")
		)
		(fp_line
			(start -0.67945 0.3048)
			(end -0.120396 0.3048)
			(stroke
				(width 0.1)
				(type default)
			)
			(layer "B.Fab")
		)
		(fp_line
			(start -0.120396 0.3048)
			(end -0.120396 0.2794)
			(stroke
				(width 0.1)
				(type default)
			)
			(layer "B.Fab")
		)
		(fp_line
			(start 0.12065 0.3048)
			(end 0.67945 0.3048)
			(stroke
				(width 0.1)
				(type default)
			)
			(layer "B.Fab")
		)
		(fp_line
			(start 0.67945 0.3048)
			(end 0.67945 -0.305054)
			(stroke
				(width 0.1)
				(type default)
			)
			(layer "B.Fab")
		)
		(fp_line
			(start -0.120396 0.2794)
			(end 0.12065 0.2794)
			(stroke
				(width 0.1)
				(type default)
			)
			(layer "B.Fab")
		)
		(fp_line
			(start 0.12065 0.2794)
			(end 0.12065 0.3048)
			(stroke
				(width 0.1)
				(type default)
			)
			(layer "B.Fab")
		)
		(fp_line
			(start -0.12065 -0.2794)
			(end -0.12065 -0.3048)
			(stroke
				(width 0.1)
				(type default)
			)
			(layer "B.Fab")
		)
		(fp_line
			(start 0.12065 -0.2794)
			(end -0.12065 -0.2794)
			(stroke
				(width 0.1)
				(type default)
			)
			(layer "B.Fab")
		)
		(fp_line
			(start -0.67945 -0.3048)
			(end -0.67945 0.3048)
			(stroke
				(width 0.1)
				(type default)
			)
			(layer "B.Fab")
		)
		(fp_line
			(start -0.12065 -0.3048)
			(end -0.67945 -0.3048)
			(stroke
				(width 0.1)
				(type default)
			)
			(layer "B.Fab")
		)
		(fp_line
			(start 0.12065 -0.305054)
			(end 0.12065 -0.2794)
			(stroke
				(width 0.1)
				(type default)
			)
			(layer "B.Fab")
		)
		(fp_line
			(start 0.67945 -0.305054)
			(end 0.12065 -0.305054)
			(stroke
				(width 0.1)
				(type default)
			)
			(layer "B.Fab")
		)
		(pad "1" smd circle
			(at 0.40005 0 90)
			(size 0 0)
			(layers "B.Cu" "B.Mask" "B.Paste")
			(net "FM_PVDDCR_CPU1_P0_EN")
		)
		(pad "2" smd circle
			(at -0.40005 0 90)
			(size 0 0)
			(layers "B.Cu" "B.Mask" "B.Paste")
			(net "FM_PVDDCR_CPU1_P0_R_EN")
		)
	)
	(footprint ""
		(layer "B.Cu")
		(at 278.713184 -337.984846 -90)
		(property "Reference" "PC189_4"
			(at 0 0 90)
			(layer "B.SilkS")
			(hide yes)
			(effects
				(font
					(size 1.27 1.27)
				)
				(justify mirror)
			)
		)
		(property "Value" ""
			(at 0 0 90)
			(layer "B.Fab")
			(effects
				(font
					(size 1.27 1.27)
				)
				(justify mirror)
			)
		)
		(duplicate_pad_numbers_are_jumpers no)
		(fp_line
			(start -1.524 0.762)
			(end 1.524 0.762)
			(stroke
				(width 0.1524)
				(type default)
			)
			(layer "B.SilkS")
		)
		(fp_line
			(start 1.524 0.762)
			(end 1.524 -0.762)
			(stroke
				(width 0.1524)
				(type default)
			)
			(layer "B.SilkS")
		)
		(fp_line
			(start -1.524 -0.762)
			(end -1.524 0.762)
			(stroke
				(width 0.1524)
				(type default)
			)
			(layer "B.SilkS")
		)
		(fp_line
			(start 1.524 -0.762)
			(end -1.524 -0.762)
			(stroke
				(width 0.1524)
				(type default)
			)
			(layer "B.SilkS")
		)
		(fp_line
			(start -1.1049 0.724916)
			(end -1.1049 -0.724916)
			(stroke
				(width 0.1)
				(type default)
			)
			(layer "B.Fab")
		)
		(fp_line
			(start 1.1049 0.724916)
			(end -1.1049 0.724916)
			(stroke
				(width 0.1)
				(type default)
			)
			(layer "B.Fab")
		)
		(fp_line
			(start -1.1049 -0.724916)
			(end 1.1049 -0.724916)
			(stroke
				(width 0.1)
				(type default)
			)
			(layer "B.Fab")
		)
		(fp_line
			(start 1.1049 -0.724916)
			(end 1.1049 0.724916)
			(stroke
				(width 0.1)
				(type default)
			)
			(layer "B.Fab")
		)
		(pad "1" smd rect
			(at 0.889 0 270)
			(size 1.016 1.27)
			(layers "B.Cu" "B.Mask" "B.Paste")
			(net "PVDDIO_P0")
		)
		(pad "2" smd rect
			(at -0.889 0 270)
			(size 1.016 1.27)
			(layers "B.Cu" "B.Mask" "B.Paste")
			(net "GND")
		)
	)
	(footprint ""
		(layer "B.Cu")
		(at 105.577386 -269.307564)
		(property "Reference" "C2351"
			(at 0 0 0)
			(layer "B.SilkS")
			(hide yes)
			(effects
				(font
					(size 1.27 1.27)
				)
				(justify mirror)
			)
		)
		(property "Value" ""
			(at 0 0 0)
			(layer "B.Fab")
			(effects
				(font
					(size 1.27 1.27)
				)
				(justify mirror)
			)
		)
		(duplicate_pad_numbers_are_jumpers no)
		(fp_line
			(start -0.7874 -0.4064)
			(end -0.7874 0.4064)
			(stroke
				(width 0.1524)
				(type default)
			)
			(layer "B.SilkS")
		)
		(fp_line
			(start -0.7874 0.4064)
			(end 0.7874 0.4064)
			(stroke
				(width 0.1524)
				(type default)
			)
			(layer "B.SilkS")
		)
		(fp_line
			(start 0.7874 -0.4064)
			(end -0.7874 -0.4064)
			(stroke
				(width 0.1524)
				(type default)
			)
			(layer "B.SilkS")
		)
		(fp_line
			(start 0.7874 0.4064)
			(end 0.7874 -0.4064)
			(stroke
				(width 0.1524)
				(type default)
			)
			(layer "B.SilkS")
		)
		(fp_line
			(start -0.67945 -0.3048)
			(end -0.67945 0.3048)
			(stroke
				(width 0.1)
				(type default)
			)
			(layer "B.Fab")
		)
		(fp_line
			(start -0.67945 0.3048)
			(end -0.120396 0.3048)
			(stroke
				(width 0.1)
				(type default)
			)
			(layer "B.Fab")
		)
		(fp_line
			(start -0.12065 -0.3048)
			(end -0.67945 -0.3048)
			(stroke
				(width 0.1)
				(type default)
			)
			(layer "B.Fab")
		)
		(fp_line
			(start -0.12065 -0.2794)
			(end -0.12065 -0.3048)
			(stroke
				(width 0.1)
				(type default)
			)
			(layer "B.Fab")
		)
		(fp_line
			(start -0.120396 0.2794)
			(end 0.12065 0.2794)
			(stroke
				(width 0.1)
				(type default)
			)
			(layer "B.Fab")
		)
		(fp_line
			(start -0.120396 0.3048)
			(end -0.120396 0.2794)
			(stroke
				(width 0.1)
				(type default)
			)
			(layer "B.Fab")
		)
		(fp_line
			(start 0.12065 -0.305054)
			(end 0.12065 -0.2794)
			(stroke
				(width 0.1)
				(type default)
			)
			(layer "B.Fab")
		)
		(fp_line
			(start 0.12065 -0.2794)
			(end -0.12065 -0.2794)
			(stroke
				(width 0.1)
				(type default)
			)
			(layer "B.Fab")
		)
		(fp_line
			(start 0.12065 0.2794)
			(end 0.12065 0.3048)
			(stroke
				(width 0.1)
				(type default)
			)
			(layer "B.Fab")
		)
		(fp_line
			(start 0.12065 0.3048)
			(end 0.67945 0.3048)
			(stroke
				(width 0.1)
				(type default)
			)
			(layer "B.Fab")
		)
		(fp_line
			(start 0.67945 -0.305054)
			(end 0.12065 -0.305054)
			(stroke
				(width 0.1)
				(type default)
			)
			(layer "B.Fab")
		)
		(fp_line
			(start 0.67945 0.3048)
			(end 0.67945 -0.305054)
			(stroke
				(width 0.1)
				(type default)
			)
			(layer "B.Fab")
		)
		(pad "1" smd circle
			(at 0.40005 0 180)
			(size 0 0)
			(layers "B.Cu" "B.Mask" "B.Paste")
			(net "PVDDCR_CPU1_P1")
		)
		(pad "2" smd circle
			(at -0.40005 0 180)
			(size 0 0)
			(layers "B.Cu" "B.Mask" "B.Paste")
			(net "GND")
		)
	)
	(footprint ""
		(layer "B.Cu")
		(at 109.095794 -384.66268 180)
		(property "Reference" "R920"
			(at 0 0 0)
			(layer "B.SilkS")
			(hide yes)
			(effects
				(font
					(size 1.27 1.27)
				)
				(justify mirror)
			)
		)
		(property "Value" ""
			(at 0 0 0)
			(layer "B.Fab")
			(effects
				(font
					(size 1.27 1.27)
				)
				(justify mirror)
			)
		)
		(duplicate_pad_numbers_are_jumpers no)
		(fp_line
			(start 0.32512 0.175006)
			(end 0.32512 -0.175006)
			(stroke
				(width 0.1)
				(type default)
			)
			(layer "B.Fab")
		)
		(fp_line
			(start 0.32512 -0.175006)
			(end -0.32512 -0.175006)
			(stroke
				(width 0.1)
				(type default)
			)
			(layer "B.Fab")
		)
		(fp_line
			(start -0.32512 0.175006)
			(end 0.32512 0.175006)
			(stroke
				(width 0.1)
				(type default)
			)
			(layer "B.Fab")
		)
		(fp_line
			(start -0.32512 -0.175006)
			(end -0.32512 0.175006)
			(stroke
				(width 0.1)
				(type default)
			)
			(layer "B.Fab")
		)
		(pad "1" smd rect
			(at 0.2667 0)
			(size 0.3048 0.381)
			(layers "B.Cu" "B.Mask" "B.Paste")
			(net "P1V8_CPU1_RT_1D")
		)
		(pad "2" smd rect
			(at -0.2667 0 180)
			(size 0.3048 0.381)
			(layers "B.Cu" "B.Mask" "B.Paste")
			(net "TEST1_RT_CPU1_P3")
		)
	)
	(footprint ""
		(layer "B.Cu")
		(at 235.077 -234.061 90)
		(property "Reference" "R1162"
			(at 0 0 90)
			(layer "B.SilkS")
			(hide yes)
			(effects
				(font
					(size 1.27 1.27)
				)
				(justify mirror)
			)
		)
		(property "Value" ""
			(at 0 0 90)
			(layer "B.Fab")
			(effects
				(font
					(size 1.27 1.27)
				)
				(justify mirror)
			)
		)
		(duplicate_pad_numbers_are_jumpers no)
		(fp_line
			(start 0.7874 -0.4064)
			(end -0.7874 -0.4064)
			(stroke
				(width 0.1524)
				(type default)
			)
			(layer "B.SilkS")
		)
		(fp_line
			(start -0.7874 -0.4064)
			(end -0.7874 0.4064)
			(stroke
				(width 0.1524)
				(type default)
			)
			(layer "B.SilkS")
		)
		(fp_line
			(start 0.7874 0.4064)
			(end 0.7874 -0.4064)
			(stroke
				(width 0.1524)
				(type default)
			)
			(layer "B.SilkS")
		)
		(fp_line
			(start -0.7874 0.4064)
			(end 0.7874 0.4064)
			(stroke
				(width 0.1524)
				(type default)
			)
			(layer "B.SilkS")
		)
		(fp_line
			(start 0.67945 -0.305054)
			(end 0.12065 -0.305054)
			(stroke
				(width 0.1)
				(type default)
			)
			(layer "B.Fab")
		)
		(fp_line
			(start 0.12065 -0.305054)
			(end 0.12065 -0.2794)
			(stroke
				(width 0.1)
				(type default)
			)
			(layer "B.Fab")
		)
		(fp_line
			(start -0.12065 -0.3048)
			(end -0.67945 -0.3048)
			(stroke
				(width 0.1)
				(type default)
			)
			(layer "B.Fab")
		)
		(fp_line
			(start -0.67945 -0.3048)
			(end -0.67945 0.3048)
			(stroke
				(width 0.1)
				(type default)
			)
			(layer "B.Fab")
		)
		(fp_line
			(start 0.12065 -0.2794)
			(end -0.12065 -0.2794)
			(stroke
				(width 0.1)
				(type default)
			)
			(layer "B.Fab")
		)
		(fp_line
			(start -0.12065 -0.2794)
			(end -0.12065 -0.3048)
			(stroke
				(width 0.1)
				(type default)
			)
			(layer "B.Fab")
		)
		(fp_line
			(start 0.12065 0.2794)
			(end 0.12065 0.3048)
			(stroke
				(width 0.1)
				(type default)
			)
			(layer "B.Fab")
		)
		(fp_line
			(start -0.120396 0.2794)
			(end 0.12065 0.2794)
			(stroke
				(width 0.1)
				(type default)
			)
			(layer "B.Fab")
		)
		(fp_line
			(start 0.67945 0.3048)
			(end 0.67945 -0.305054)
			(stroke
				(width 0.1)
				(type default)
			)
			(layer "B.Fab")
		)
		(fp_line
			(start 0.12065 0.3048)
			(end 0.67945 0.3048)
			(stroke
				(width 0.1)
				(type default)
			)
			(layer "B.Fab")
		)
		(fp_line
			(start -0.120396 0.3048)
			(end -0.120396 0.2794)
			(stroke
				(width 0.1)
				(type default)
			)
			(layer "B.Fab")
		)
		(fp_line
			(start -0.67945 0.3048)
			(end -0.120396 0.3048)
			(stroke
				(width 0.1)
				(type default)
			)
			(layer "B.Fab")
		)
		(pad "1" smd circle
			(at 0.40005 0 270)
			(size 0 0)
			(layers "B.Cu" "B.Mask" "B.Paste")
			(net "SMB_CPU1_SEC_R_SDA")
		)
		(pad "2" smd circle
			(at -0.40005 0 270)
			(size 0 0)
			(layers "B.Cu" "B.Mask" "B.Paste")
			(net "SMB_CPU1_SEC_SDA")
		)
	)
	(footprint ""
		(layer "B.Cu")
		(at 347.918786 -399.291302 90)
		(property "Reference" "C655"
			(at 0 0 90)
			(layer "B.SilkS")
			(hide yes)
			(effects
				(font
					(size 1.27 1.27)
				)
				(justify mirror)
			)
		)
		(property "Value" ""
			(at 0 0 90)
			(layer "B.Fab")
			(effects
				(font
					(size 1.27 1.27)
				)
				(justify mirror)
			)
		)
		(duplicate_pad_numbers_are_jumpers no)
		(fp_line
			(start 0.299974 -0.150114)
			(end -0.299974 -0.150114)
			(stroke
				(width 0.1)
				(type default)
			)
			(layer "B.Fab")
		)
		(fp_line
			(start -0.299974 -0.150114)
			(end -0.299974 0.150114)
			(stroke
				(width 0.1)
				(type default)
			)
			(layer "B.Fab")
		)
		(fp_line
			(start 0.299974 0.150114)
			(end 0.299974 -0.150114)
			(stroke
				(width 0.1)
				(type default)
			)
			(layer "B.Fab")
		)
		(fp_line
			(start -0.299974 0.150114)
			(end 0.299974 0.150114)
			(stroke
				(width 0.1)
				(type default)
			)
			(layer "B.Fab")
		)
		(pad "1" smd rect
			(at 0.2667 0 270)
			(size 0.3048 0.381)
			(layers "B.Cu" "B.Mask" "B.Paste")
			(net "P0V9_CPU0_RT_2D")
		)
		(pad "2" smd rect
			(at -0.2667 0 270)
			(size 0.3048 0.381)
			(layers "B.Cu" "B.Mask" "B.Paste")
			(net "GND")
		)
	)
)
